(kicad_pcb
	(version 20260206)
	(generator "pcbnew")
	(generator_version "10.0")
	(general
		(thickness 1.6)
		(legacy_teardrops no)
	)
	(paper "A4")
	(title_block
		(title "v1-chassis-manager — T6M_CM_d_v01_1031_1645.brd")
		(comment 1 "Open CloudServer (Microsoft) / footprints 485-494 of 2512")
	)
	(layers
		(0 "F.Cu" signal "TOP")
		(4 "In1.Cu" signal "GND1")
		(6 "In2.Cu" signal "IN1")
		(8 "In3.Cu" signal "VCC1")
		(10 "In4.Cu" signal "VCC2")
		(12 "In5.Cu" signal "GND2")
		(14 "In6.Cu" signal "IN2")
		(16 "In7.Cu" signal "IN3")
		(18 "In8.Cu" signal "GND3")
		(2 "B.Cu" signal "BOTTOM")
		(9 "F.Adhes" user "F.Adhesive")
		(11 "B.Adhes" user "B.Adhesive")
		(13 "F.Paste" user "Package Geometry/Pastemask Top")
		(15 "B.Paste" user "Package Geometry/Pastemask Bottom")
		(5 "F.SilkS" user "Ref Des/Silkscreen Top")
		(7 "B.SilkS" user "Ref Des/Silkscreen Bottom")
		(1 "F.Mask" user "Board Geometry/Soldermask Top")
		(3 "B.Mask" user "Board Geometry/Soldermask Bottom")
		(17 "Dwgs.User" user "User.Drawings")
		(19 "Cmts.User" user "User.Comments")
		(21 "Eco1.User" user "User.Eco1")
		(23 "Eco2.User" user "User.Eco2")
		(25 "Edge.Cuts" user "Board Geometry/Outline")
		(27 "Margin" user)
		(31 "F.CrtYd" user "Package Geometry/Place Bound Top")
		(29 "B.CrtYd" user "Package Geometry/Place Bound Bottom")
		(35 "F.Fab" user "Ref Des/Assembly Top")
		(33 "B.Fab" user "Ref Des/Assembly Bottom")
	)
	(footprint ""
		(layer "F.Cu")
		(at 106.082084 -154.823668 180)
		(property "Reference" "PC40"
			(at 2.189226 -4.749038 0)
			(unlocked yes)
			(layer "F.SilkS")
			(effects
				(font
					(size 0.635 0.4064)
					(thickness 0.1524)
				)
				(justify left)
			)
		)
		(property "Value" ""
			(at 0 0 180)
			(layer "F.Fab")
			(effects
				(font
					(size 1.27 1.27)
				)
			)
		)
		(duplicate_pad_numbers_are_jumpers no)
		(fp_line
			(start 0.7874 0.4064)
			(end -0.7874 0.4064)
			(stroke
				(width 0.1524)
				(type default)
			)
			(layer "F.SilkS")
		)
		(fp_line
			(start 0.7874 -0.4064)
			(end 0.7874 0.4064)
			(stroke
				(width 0.1524)
				(type default)
			)
			(layer "F.SilkS")
		)
		(fp_line
			(start 0 0.381)
			(end 0 -0.381)
			(stroke
				(width 0.1524)
				(type default)
			)
			(layer "F.SilkS")
		)
		(fp_line
			(start -0.7874 0.4064)
			(end -0.7874 -0.4064)
			(stroke
				(width 0.1524)
				(type default)
			)
			(layer "F.SilkS")
		)
		(fp_line
			(start -0.7874 -0.4064)
			(end 0.7874 -0.4064)
			(stroke
				(width 0.1524)
				(type default)
			)
			(layer "F.SilkS")
		)
		(fp_poly
			(pts
				(xy -0.5334 0.254) (xy -0.635 0.254) (xy -0.635 0.2286) (xy -0.635 -0.254) (xy -0.5334 -0.254) (xy -0.5334 -0.2794)
				(xy 0.5334 -0.2794) (xy 0.5334 -0.254) (xy 0.635 -0.254) (xy 0.635 0.254) (xy 0.5334 0.254) (xy 0.5334 0.2794)
				(xy -0.508 0.2794) (xy -0.5334 0.2794)
			)
			(stroke
				(width 0)
				(type default)
			)
			(fill no)
			(layer "F.CrtYd")
		)
		(pad "1" smd rect
			(at 0.40005 0 180)
			(size 0.4572 0.508)
			(layers "F.Cu" "F.Mask" "F.Paste")
			(net "P1V8_STB_NODE1_VREG5")
		)
		(pad "2" smd rect
			(at -0.40005 0 180)
			(size 0.4572 0.508)
			(layers "F.Cu" "F.Mask" "F.Paste")
			(net "GND")
		)
	)
	(footprint ""
		(layer "F.Cu")
		(at 132.207 -51.435 -90)
		(property "Reference" "R1163"
			(at -16.3322 -30.65907 90)
			(unlocked yes)
			(layer "F.SilkS")
			(effects
				(font
					(size 0.7874 0.5842)
					(thickness 0.1524)
				)
				(justify left)
			)
		)
		(property "Value" ""
			(at 0 0 270)
			(layer "F.Fab")
			(effects
				(font
					(size 1.27 1.27)
				)
			)
		)
		(duplicate_pad_numbers_are_jumpers no)
		(fp_line
			(start -0.7874 0.4064)
			(end -0.7874 -0.4064)
			(stroke
				(width 0.1524)
				(type default)
			)
			(layer "F.SilkS")
		)
		(fp_line
			(start 0.7874 0.4064)
			(end -0.7874 0.4064)
			(stroke
				(width 0.1524)
				(type default)
			)
			(layer "F.SilkS")
		)
		(fp_line
			(start -0.7874 -0.4064)
			(end 0.7874 -0.4064)
			(stroke
				(width 0.1524)
				(type default)
			)
			(layer "F.SilkS")
		)
		(fp_line
			(start 0.7874 -0.4064)
			(end 0.7874 0.4064)
			(stroke
				(width 0.1524)
				(type default)
			)
			(layer "F.SilkS")
		)
		(fp_poly
			(pts
				(xy -0.508 0.2794) (xy -0.508 0.2286) (xy -0.635 0.2286) (xy -0.635 -0.254) (xy -0.5334 -0.254)
				(xy -0.5334 -0.2794) (xy 0.5334 -0.2794) (xy 0.5334 -0.254) (xy 0.635 -0.254) (xy 0.635 0.254) (xy 0.5334 0.254)
				(xy 0.5334 0.2794)
			)
			(stroke
				(width 0)
				(type default)
			)
			(fill no)
			(layer "F.CrtYd")
		)
		(pad "1" smd rect
			(at 0.40005 0 270)
			(size 0.4572 0.508)
			(layers "F.Cu" "F.Mask" "F.Paste")
			(net "UART_DTR_P4_R_N")
		)
		(pad "2" smd rect
			(at -0.40005 0 270)
			(size 0.4572 0.508)
			(layers "F.Cu" "F.Mask" "F.Paste")
			(net "UART_DTR_P4_N")
		)
	)
	(footprint ""
		(layer "F.Cu")
		(at 87.68588 -76.013564 180)
		(property "Reference" "C61"
			(at -2.86004 -0.087376 0)
			(unlocked yes)
			(layer "F.SilkS")
			(effects
				(font
					(size 0.7874 0.5842)
					(thickness 0.1524)
				)
				(justify left)
			)
		)
		(property "Value" ""
			(at 0 0 180)
			(layer "F.Fab")
			(effects
				(font
					(size 1.27 1.27)
				)
			)
		)
		(duplicate_pad_numbers_are_jumpers no)
		(fp_line
			(start 0.7874 0.4064)
			(end -0.7874 0.4064)
			(stroke
				(width 0.1524)
				(type default)
			)
			(layer "F.SilkS")
		)
		(fp_line
			(start 0.7874 -0.4064)
			(end 0.7874 0.4064)
			(stroke
				(width 0.1524)
				(type default)
			)
			(layer "F.SilkS")
		)
		(fp_line
			(start 0 0.381)
			(end 0 -0.381)
			(stroke
				(width 0.1524)
				(type default)
			)
			(layer "F.SilkS")
		)
		(fp_line
			(start -0.7874 0.4064)
			(end -0.7874 -0.4064)
			(stroke
				(width 0.1524)
				(type default)
			)
			(layer "F.SilkS")
		)
		(fp_line
			(start -0.7874 -0.4064)
			(end 0.7874 -0.4064)
			(stroke
				(width 0.1524)
				(type default)
			)
			(layer "F.SilkS")
		)
		(fp_poly
			(pts
				(xy -0.5334 0.254) (xy -0.635 0.254) (xy -0.635 0.2286) (xy -0.635 -0.254) (xy -0.5334 -0.254) (xy -0.5334 -0.2794)
				(xy 0.5334 -0.2794) (xy 0.5334 -0.254) (xy 0.635 -0.254) (xy 0.635 0.254) (xy 0.5334 0.254) (xy 0.5334 0.2794)
				(xy -0.508 0.2794) (xy -0.5334 0.2794)
			)
			(stroke
				(width 0)
				(type default)
			)
			(fill no)
			(layer "F.CrtYd")
		)
		(pad "1" smd rect
			(at 0.40005 0 180)
			(size 0.4572 0.508)
			(layers "F.Cu" "F.Mask" "F.Paste")
			(net "P1V05_VCCPLLCPU0SIO_NODE1")
		)
		(pad "2" smd rect
			(at -0.40005 0 180)
			(size 0.4572 0.508)
			(layers "F.Cu" "F.Mask" "F.Paste")
			(net "GND")
		)
	)
	(footprint ""
		(layer "F.Cu")
		(at 155.356814 -65.482216)
		(property "Reference" "C490"
			(at -0.53086 2.179574 0)
			(unlocked yes)
			(layer "F.SilkS")
			(effects
				(font
					(size 0.7874 0.5842)
					(thickness 0.1524)
				)
				(justify left)
			)
		)
		(property "Value" ""
			(at 0 0 0)
			(layer "F.Fab")
			(effects
				(font
					(size 1.27 1.27)
				)
			)
		)
		(duplicate_pad_numbers_are_jumpers no)
		(fp_line
			(start -0.7874 -0.4064)
			(end 0.7874 -0.4064)
			(stroke
				(width 0.1524)
				(type default)
			)
			(layer "F.SilkS")
		)
		(fp_line
			(start -0.7874 0.4064)
			(end -0.7874 -0.4064)
			(stroke
				(width 0.1524)
				(type default)
			)
			(layer "F.SilkS")
		)
		(fp_line
			(start 0 0.381)
			(end 0 -0.381)
			(stroke
				(width 0.1524)
				(type default)
			)
			(layer "F.SilkS")
		)
		(fp_line
			(start 0.7874 -0.4064)
			(end 0.7874 0.4064)
			(stroke
				(width 0.1524)
				(type default)
			)
			(layer "F.SilkS")
		)
		(fp_line
			(start 0.7874 0.4064)
			(end -0.7874 0.4064)
			(stroke
				(width 0.1524)
				(type default)
			)
			(layer "F.SilkS")
		)
		(fp_poly
			(pts
				(xy -0.5334 0.254) (xy -0.635 0.254) (xy -0.635 0.2286) (xy -0.635 -0.254) (xy -0.5334 -0.254) (xy -0.5334 -0.2794)
				(xy 0.5334 -0.2794) (xy 0.5334 -0.254) (xy 0.635 -0.254) (xy 0.635 0.254) (xy 0.5334 0.254) (xy 0.5334 0.2794)
				(xy -0.508 0.2794) (xy -0.5334 0.2794)
			)
			(stroke
				(width 0)
				(type default)
			)
			(fill no)
			(layer "F.CrtYd")
		)
		(pad "1" smd rect
			(at 0.40005 0)
			(size 0.4572 0.508)
			(layers "F.Cu" "F.Mask" "F.Paste")
			(net "SATA_TX0_C_DN")
		)
		(pad "2" smd rect
			(at -0.40005 0)
			(size 0.4572 0.508)
			(layers "F.Cu" "F.Mask" "F.Paste")
			(net "SATA_A_NODE1_TX_N0")
		)
	)
	(footprint ""
		(layer "F.Cu")
		(at 116.075714 -139.122912 180)
		(property "Reference" "PJ14"
			(at -2.973832 4.671568 90)
			(unlocked yes)
			(layer "F.SilkS")
			(effects
				(font
					(size 0.7874 0.5842)
					(thickness 0.1524)
				)
				(justify left)
			)
		)
		(property "Value" ""
			(at 0 0 180)
			(layer "F.Fab")
			(effects
				(font
					(size 1.27 1.27)
				)
			)
		)
		(duplicate_pad_numbers_are_jumpers no)
		(fp_poly
			(pts
				(xy -0.360426 0.359156) (xy -0.360426 -0.381) (xy 0.3556 -0.381) (xy 0.3556 1.905) (xy -0.360426 1.905)
			)
			(stroke
				(width 0)
				(type default)
			)
			(fill no)
			(layer "F.CrtYd")
		)
		(pad "1" smd custom
			(at 0 0 180)
			(size 0.1778 0.1778)
			(layers "F.Cu" "F.Mask" "F.Paste")
			(net "VR_PVCCP_NODE1_VSEN")
			(options
				(clearance outline)
				(anchor circle)
			)
			(primitives
				(gr_poly
					(pts
						(xy -0.127 0.9398) (xy -0.127 -0.127) (xy -0.3556 -0.127) (xy -0.3556 -0.9398) (xy 0.3556 -0.9398)
						(xy 0.3556 -0.127) (xy 0.127 -0.127) (xy 0.127 0.9398)
					)
					(width 0)
					(fill yes)
				)
			)
		)
		(pad "2" smd rect
			(at 0 1.4986)
			(size 0.7112 0.8128)
			(layers "F.Cu" "F.Mask" "F.Paste")
			(net "VSENSE_VCC_CPU_NODE1")
		)
		(zone
			(layer "F.Cu")
			(hatch none 0.5)
			(connect_pads
				(clearance 0)
			)
			(min_thickness 0.25)
			(keepout
				(tracks allowed)
				(vias not_allowed)
				(pads allowed)
				(copperpour not_allowed)
				(footprints allowed)
			)
			(placement
				(enabled no)
				(sheetname "")
			)
			(fill
				(thermal_gap 0.5)
				(thermal_bridge_width 0.5)
				(island_removal_mode 0)
			)
			(polygon
				(pts
					(xy 115.669314 -141.078712) (xy 115.669314 -138.691112) (xy 116.48694 -138.691112) (xy 116.48694 -141.078712)
				)
			)
		)
	)
	(footprint ""
		(layer "F.Cu")
		(at 90.812112 -172.499782 180)
		(property "Reference" "R942"
			(at -85.974428 -74.448162 0)
			(unlocked yes)
			(layer "F.SilkS")
			(effects
				(font
					(size 0.7874 0.5842)
					(thickness 0.1524)
				)
				(justify left)
			)
		)
		(property "Value" ""
			(at 0 0 180)
			(layer "F.Fab")
			(effects
				(font
					(size 1.27 1.27)
				)
			)
		)
		(duplicate_pad_numbers_are_jumpers no)
		(fp_line
			(start 0.7874 0.4064)
			(end -0.7874 0.4064)
			(stroke
				(width 0.1524)
				(type default)
			)
			(layer "F.SilkS")
		)
		(fp_line
			(start 0.7874 -0.4064)
			(end 0.7874 0.4064)
			(stroke
				(width 0.1524)
				(type default)
			)
			(layer "F.SilkS")
		)
		(fp_line
			(start -0.7874 0.4064)
			(end -0.7874 -0.4064)
			(stroke
				(width 0.1524)
				(type default)
			)
			(layer "F.SilkS")
		)
		(fp_line
			(start -0.7874 -0.4064)
			(end 0.7874 -0.4064)
			(stroke
				(width 0.1524)
				(type default)
			)
			(layer "F.SilkS")
		)
		(fp_poly
			(pts
				(xy -0.508 0.2794) (xy -0.508 0.2286) (xy -0.635 0.2286) (xy -0.635 -0.254) (xy -0.5334 -0.254)
				(xy -0.5334 -0.2794) (xy 0.5334 -0.2794) (xy 0.5334 -0.254) (xy 0.635 -0.254) (xy 0.635 0.254) (xy 0.5334 0.254)
				(xy 0.5334 0.2794)
			)
			(stroke
				(width 0)
				(type default)
			)
			(fill no)
			(layer "F.CrtYd")
		)
		(pad "1" smd rect
			(at 0.40005 0 180)
			(size 0.4572 0.508)
			(layers "F.Cu" "F.Mask" "F.Paste")
			(net "UART_T6_NODE2_TXD")
		)
		(pad "2" smd rect
			(at -0.40005 0 180)
			(size 0.4572 0.508)
			(layers "F.Cu" "F.Mask" "F.Paste")
			(net "UART_T6_NODE2_TXD_R")
		)
	)
	(footprint ""
		(layer "F.Cu")
		(at 138.79576 -188.126624 90)
		(property "Reference" "C642"
			(at 5.519674 -0.214376 90)
			(unlocked yes)
			(layer "F.SilkS")
			(effects
				(font
					(size 0.7874 0.5842)
					(thickness 0.1524)
				)
				(justify left)
			)
		)
		(property "Value" ""
			(at 0 0 90)
			(layer "F.Fab")
			(effects
				(font
					(size 1.27 1.27)
				)
			)
		)
		(duplicate_pad_numbers_are_jumpers no)
		(fp_line
			(start 0.7874 -0.4064)
			(end 0.7874 0.4064)
			(stroke
				(width 0.1524)
				(type default)
			)
			(layer "F.SilkS")
		)
		(fp_line
			(start -0.7874 -0.4064)
			(end 0.7874 -0.4064)
			(stroke
				(width 0.1524)
				(type default)
			)
			(layer "F.SilkS")
		)
		(fp_line
			(start 0 0.381)
			(end 0 -0.381)
			(stroke
				(width 0.1524)
				(type default)
			)
			(layer "F.SilkS")
		)
		(fp_line
			(start 0.7874 0.4064)
			(end -0.7874 0.4064)
			(stroke
				(width 0.1524)
				(type default)
			)
			(layer "F.SilkS")
		)
		(fp_line
			(start -0.7874 0.4064)
			(end -0.7874 -0.4064)
			(stroke
				(width 0.1524)
				(type default)
			)
			(layer "F.SilkS")
		)
		(fp_poly
			(pts
				(xy -0.5334 0.254) (xy -0.635 0.254) (xy -0.635 0.2286) (xy -0.635 -0.254) (xy -0.5334 -0.254) (xy -0.5334 -0.2794)
				(xy 0.5334 -0.2794) (xy 0.5334 -0.254) (xy 0.635 -0.254) (xy 0.635 0.254) (xy 0.5334 0.254) (xy 0.5334 0.2794)
				(xy -0.508 0.2794) (xy -0.5334 0.2794)
			)
			(stroke
				(width 0)
				(type default)
			)
			(fill no)
			(layer "F.CrtYd")
		)
		(pad "1" smd rect
			(at 0.40005 0 90)
			(size 0.4572 0.508)
			(layers "F.Cu" "F.Mask" "F.Paste")
			(net "T10_NODE3_EN_R")
		)
		(pad "2" smd rect
			(at -0.40005 0 90)
			(size 0.4572 0.508)
			(layers "F.Cu" "F.Mask" "F.Paste")
			(net "GND")
		)
	)
	(footprint ""
		(layer "F.Cu")
		(at 102.149656 -17.68094 180)
		(property "Reference" "C140"
			(at -1.48717 -3.301746 90)
			(unlocked yes)
			(layer "F.SilkS")
			(effects
				(font
					(size 0.7874 0.5842)
					(thickness 0.1524)
				)
				(justify left)
			)
		)
		(property "Value" ""
			(at 0 0 180)
			(layer "F.Fab")
			(effects
				(font
					(size 1.27 1.27)
				)
			)
		)
		(duplicate_pad_numbers_are_jumpers no)
		(fp_line
			(start 0.7874 0.4064)
			(end -0.7874 0.4064)
			(stroke
				(width 0.1524)
				(type default)
			)
			(layer "F.SilkS")
		)
		(fp_line
			(start 0.7874 -0.4064)
			(end 0.7874 0.4064)
			(stroke
				(width 0.1524)
				(type default)
			)
			(layer "F.SilkS")
		)
		(fp_line
			(start 0 0.381)
			(end 0 -0.381)
			(stroke
				(width 0.1524)
				(type default)
			)
			(layer "F.SilkS")
		)
		(fp_line
			(start -0.7874 0.4064)
			(end -0.7874 -0.4064)
			(stroke
				(width 0.1524)
				(type default)
			)
			(layer "F.SilkS")
		)
		(fp_line
			(start -0.7874 -0.4064)
			(end 0.7874 -0.4064)
			(stroke
				(width 0.1524)
				(type default)
			)
			(layer "F.SilkS")
		)
		(fp_poly
			(pts
				(xy -0.5334 0.254) (xy -0.635 0.254) (xy -0.635 0.2286) (xy -0.635 -0.254) (xy -0.5334 -0.254) (xy -0.5334 -0.2794)
				(xy 0.5334 -0.2794) (xy 0.5334 -0.254) (xy 0.635 -0.254) (xy 0.635 0.254) (xy 0.5334 0.254) (xy 0.5334 0.2794)
				(xy -0.508 0.2794) (xy -0.5334 0.2794)
			)
			(stroke
				(width 0)
				(type default)
			)
			(fill no)
			(layer "F.CrtYd")
		)
		(pad "1" smd rect
			(at 0.40005 0 180)
			(size 0.4572 0.508)
			(layers "F.Cu" "F.Mask" "F.Paste")
			(net "P3V3_NODE1")
		)
		(pad "2" smd rect
			(at -0.40005 0 180)
			(size 0.4572 0.508)
			(layers "F.Cu" "F.Mask" "F.Paste")
			(net "GND")
		)
	)
	(footprint ""
		(layer "F.Cu")
		(at 102.009448 -136.176258)
		(property "Reference" "PR52"
			(at -4.386834 -8.420608 0)
			(unlocked yes)
			(layer "F.SilkS")
			(effects
				(font
					(size 0.7874 0.5842)
					(thickness 0.1524)
				)
				(justify left)
			)
		)
		(property "Value" ""
			(at 0 0 0)
			(layer "F.Fab")
			(effects
				(font
					(size 1.27 1.27)
				)
			)
		)
		(duplicate_pad_numbers_are_jumpers no)
		(fp_line
			(start -0.7874 -0.4064)
			(end 0.7874 -0.4064)
			(stroke
				(width 0.1524)
				(type default)
			)
			(layer "F.SilkS")
		)
		(fp_line
			(start -0.7874 0.4064)
			(end -0.7874 -0.4064)
			(stroke
				(width 0.1524)
				(type default)
			)
			(layer "F.SilkS")
		)
		(fp_line
			(start 0.7874 -0.4064)
			(end 0.7874 0.4064)
			(stroke
				(width 0.1524)
				(type default)
			)
			(layer "F.SilkS")
		)
		(fp_line
			(start 0.7874 0.4064)
			(end -0.7874 0.4064)
			(stroke
				(width 0.1524)
				(type default)
			)
			(layer "F.SilkS")
		)
		(fp_poly
			(pts
				(xy -0.508 0.2794) (xy -0.508 0.2286) (xy -0.635 0.2286) (xy -0.635 -0.254) (xy -0.5334 -0.254)
				(xy -0.5334 -0.2794) (xy 0.5334 -0.2794) (xy 0.5334 -0.254) (xy 0.635 -0.254) (xy 0.635 0.254) (xy 0.5334 0.254)
				(xy 0.5334 0.2794)
			)
			(stroke
				(width 0)
				(type default)
			)
			(fill no)
			(layer "F.CrtYd")
		)
		(pad "1" smd rect
			(at 0.40005 0)
			(size 0.4572 0.508)
			(layers "F.Cu" "F.Mask" "F.Paste")
			(net "PWRGD_NODE1_PVCCP_PG")
		)
		(pad "2" smd rect
			(at -0.40005 0)
			(size 0.4572 0.508)
			(layers "F.Cu" "F.Mask" "F.Paste")
			(net "P3V3_NODE1")
		)
	)
	(footprint ""
		(layer "F.Cu")
		(at 46.588426 -100.517706 -90)
		(property "Reference" "C139"
			(at 2.55397 0.97663 90)
			(unlocked yes)
			(layer "F.SilkS")
			(effects
				(font
					(size 0.7874 0.5842)
					(thickness 0.1524)
				)
				(justify left)
			)
		)
		(property "Value" ""
			(at 0 0 270)
			(layer "F.Fab")
			(effects
				(font
					(size 1.27 1.27)
				)
			)
		)
		(duplicate_pad_numbers_are_jumpers no)
		(fp_line
			(start -0.7874 0.4064)
			(end -0.7874 -0.4064)
			(stroke
				(width 0.1524)
				(type default)
			)
			(layer "F.SilkS")
		)
		(fp_line
			(start 0.7874 0.4064)
			(end -0.7874 0.4064)
			(stroke
				(width 0.1524)
				(type default)
			)
			(layer "F.SilkS")
		)
		(fp_line
			(start 0 0.381)
			(end 0 -0.381)
			(stroke
				(width 0.1524)
				(type default)
			)
			(layer "F.SilkS")
		)
		(fp_line
			(start -0.7874 -0.4064)
			(end 0.7874 -0.4064)
			(stroke
				(width 0.1524)
				(type default)
			)
			(layer "F.SilkS")
		)
		(fp_line
			(start 0.7874 -0.4064)
			(end 0.7874 0.4064)
			(stroke
				(width 0.1524)
				(type default)
			)
			(layer "F.SilkS")
		)
		(fp_poly
			(pts
				(xy -0.5334 0.254) (xy -0.635 0.254) (xy -0.635 0.2286) (xy -0.635 -0.254) (xy -0.5334 -0.254) (xy -0.5334 -0.2794)
				(xy 0.5334 -0.2794) (xy 0.5334 -0.254) (xy 0.635 -0.254) (xy 0.635 0.254) (xy 0.5334 0.254) (xy 0.5334 0.2794)
				(xy -0.508 0.2794) (xy -0.5334 0.2794)
			)
			(stroke
				(width 0)
				(type default)
			)
			(fill no)
			(layer "F.CrtYd")
		)
		(pad "1" smd rect
			(at 0.40005 0 270)
			(size 0.4572 0.508)
			(layers "F.Cu" "F.Mask" "F.Paste")
			(net "A_SOC_NODE1_THERMDA")
		)
		(pad "2" smd rect
			(at -0.40005 0 270)
			(size 0.4572 0.508)
			(layers "F.Cu" "F.Mask" "F.Paste")
			(net "A_SOC_NODE1_THERMDC")
		)
	)
)
